# S9S_MB_2U (Grand Teton) — schematic netlist excerpt (pin names and nets, part order shuffled) for the footprints in the layout excerpt that follows; sources: Cadence DE-HDL packaged netlist, KiCad conversion of 03242023_DA0F0TMBIJ0_F0T_Motherboard_J_brd_V01_OCP.brd

R601  Q_RES  2.2K 5% EMPTY  pkg 0402LF  page 241 : A = SMB_FAN_3V3AUX_SDA ; B = P3V3_AUX
C486  Q_CAP  47UF 4V 20% X6S  pkg C0805  page 79 : A = PVCCINFAON_CPU1 ; B = GND
C1406  Q_CAP  47UF 2.5V 20% X6S  pkg C0603  page 75 : A = PVNN_MAIN_CPU0 ; B = GND

(kicad_pcb
	(version 20260206)
	(generator "pcbnew")
	(generator_version "10.0")
	(general
		(thickness 1.6)
		(legacy_teardrops no)
	)
	(paper "A4")
	(title_block
		(title "03242023_DA0F0TMBIJ0_F0T_Motherboard_J_brd_V01_OCP.brd")
		(comment 1 "Grand Teton / footprints 5653-5655 of 6105")
	)
	(layers
		(0 "F.Cu" signal "TOP")
		(4 "In1.Cu" signal "GND")
		(6 "In2.Cu" signal "IN1")
		(8 "In3.Cu" signal "GND1")
		(10 "In4.Cu" signal "IN2")
		(12 "In5.Cu" signal "GND2")
		(14 "In6.Cu" signal "IN3")
		(16 "In7.Cu" signal "GND3")
		(18 "In8.Cu" signal "VCC")
		(20 "In9.Cu" signal "VCC1")
		(22 "In10.Cu" signal "GND4")
		(24 "In11.Cu" signal "IN4")
		(26 "In12.Cu" signal "GND5")
		(28 "In13.Cu" signal "IN5")
		(30 "In14.Cu" signal "GND6")
		(32 "In15.Cu" signal "IN6")
		(34 "In16.Cu" signal "GND7")
		(2 "B.Cu" signal "BOTTOM")
		(9 "F.Adhes" user "F.Adhesive")
		(11 "B.Adhes" user "B.Adhesive")
		(13 "F.Paste" user "Package Geometry/Pastemask Top")
		(15 "B.Paste" user "Package Geometry/Pastemask Bottom")
		(5 "F.SilkS" user "Ref Des/Silkscreen Top")
		(7 "B.SilkS" user "Ref Des/Silkscreen Bottom")
		(1 "F.Mask" user "Board Geometry/Soldermask Top")
		(3 "B.Mask" user "Board Geometry/Soldermask Bottom")
		(17 "Dwgs.User" user "User.Drawings")
		(19 "Cmts.User" user "User.Comments")
		(21 "Eco1.User" user "User.Eco1")
		(23 "Eco2.User" user "User.Eco2")
		(25 "Edge.Cuts" user "Board Geometry/Outline")
		(27 "Margin" user)
		(31 "F.CrtYd" user "Package Geometry/Place Bound Top")
		(29 "B.CrtYd" user "Package Geometry/Place Bound Bottom")
		(35 "F.Fab" user "Ref Des/Assembly Top")
		(33 "B.Fab" user "Ref Des/Assembly Bottom")
	)
	(footprint ""
		(layer "B.Cu")
		(at 352.730308 -237.709202 -90)
		(property "Reference" "C1406"
			(at 0 0 90)
			(layer "B.SilkS")
			(hide yes)
			(effects
				(font
					(size 1.27 1.27)
				)
				(justify mirror)
			)
		)
		(property "Value" ""
			(at 0 0 90)
			(layer "B.Fab")
			(effects
				(font
					(size 1.27 1.27)
				)
				(justify mirror)
			)
		)
		(duplicate_pad_numbers_are_jumpers no)
		(fp_line
			(start -1.2954 0.5842)
			(end 1.2954 0.5842)
			(stroke
				(width 0.1524)
				(type default)
			)
			(layer "B.SilkS")
		)
		(fp_line
			(start 1.2954 0.5842)
			(end 1.2954 -0.5842)
			(stroke
				(width 0.1524)
				(type default)
			)
			(layer "B.SilkS")
		)
		(fp_line
			(start -1.2954 -0.5842)
			(end -1.2954 0.5842)
			(stroke
				(width 0.1524)
				(type default)
			)
			(layer "B.SilkS")
		)
		(fp_line
			(start 0 -0.5842)
			(end 0 0.5842)
			(stroke
				(width 0.1524)
				(type default)
			)
			(layer "B.SilkS")
		)
		(fp_line
			(start 1.2954 -0.5842)
			(end -1.2954 -0.5842)
			(stroke
				(width 0.1524)
				(type default)
			)
			(layer "B.SilkS")
		)
		(fp_line
			(start -0.8636 0.4572)
			(end 0.8636 0.4572)
			(stroke
				(width 0.1)
				(type default)
			)
			(layer "B.Fab")
		)
		(fp_line
			(start 0.8636 0.4572)
			(end 0.8636 0.4064)
			(stroke
				(width 0.1)
				(type default)
			)
			(layer "B.Fab")
		)
		(fp_line
			(start -1.1938 0.4064)
			(end -0.8636 0.4064)
			(stroke
				(width 0.1)
				(type default)
			)
			(layer "B.Fab")
		)
		(fp_line
			(start -0.8636 0.4064)
			(end -0.8636 0.4572)
			(stroke
				(width 0.1)
				(type default)
			)
			(layer "B.Fab")
		)
		(fp_line
			(start 0.8636 0.4064)
			(end 1.1938 0.4064)
			(stroke
				(width 0.1)
				(type default)
			)
			(layer "B.Fab")
		)
		(fp_line
			(start 1.1938 0.4064)
			(end 1.1938 -0.4064)
			(stroke
				(width 0.1)
				(type default)
			)
			(layer "B.Fab")
		)
		(fp_line
			(start -1.1938 -0.4064)
			(end -1.1938 0.4064)
			(stroke
				(width 0.1)
				(type default)
			)
			(layer "B.Fab")
		)
		(fp_line
			(start -0.8636 -0.4064)
			(end -1.1938 -0.4064)
			(stroke
				(width 0.1)
				(type default)
			)
			(layer "B.Fab")
		)
		(fp_line
			(start 0.8636 -0.4064)
			(end 0.8636 -0.4572)
			(stroke
				(width 0.1)
				(type default)
			)
			(layer "B.Fab")
		)
		(fp_line
			(start 1.1938 -0.4064)
			(end 0.8636 -0.4064)
			(stroke
				(width 0.1)
				(type default)
			)
			(layer "B.Fab")
		)
		(fp_line
			(start -0.8636 -0.4572)
			(end -0.8636 -0.4064)
			(stroke
				(width 0.1)
				(type default)
			)
			(layer "B.Fab")
		)
		(fp_line
			(start 0.8636 -0.4572)
			(end -0.8636 -0.4572)
			(stroke
				(width 0.1)
				(type default)
			)
			(layer "B.Fab")
		)
		(pad "1" smd rect
			(at 0.7366 0 180)
			(size 0.7112 0.8128)
			(layers "B.Cu" "B.Mask" "B.Paste")
			(net "PVNN_MAIN_CPU0")
		)
		(pad "2" smd rect
			(at -0.7366 0 180)
			(size 0.7112 0.8128)
			(layers "B.Cu" "B.Mask" "B.Paste")
			(net "GND")
		)
	)
	(footprint ""
		(layer "B.Cu")
		(at 158.82366 -15.563088 180)
		(property "Reference" "R601"
			(at 0 0 0)
			(layer "B.SilkS")
			(hide yes)
			(effects
				(font
					(size 1.27 1.27)
				)
				(justify mirror)
			)
		)
		(property "Value" ""
			(at 0 0 0)
			(layer "B.Fab")
			(effects
				(font
					(size 1.27 1.27)
				)
				(justify mirror)
			)
		)
		(duplicate_pad_numbers_are_jumpers no)
		(fp_line
			(start 0.7874 0.4064)
			(end 0.7874 -0.4064)
			(stroke
				(width 0.1524)
				(type default)
			)
			(layer "B.SilkS")
		)
		(fp_line
			(start 0.7874 -0.4064)
			(end -0.7874 -0.4064)
			(stroke
				(width 0.1524)
				(type default)
			)
			(layer "B.SilkS")
		)
		(fp_line
			(start -0.7874 0.4064)
			(end 0.7874 0.4064)
			(stroke
				(width 0.1524)
				(type default)
			)
			(layer "B.SilkS")
		)
		(fp_line
			(start -0.7874 -0.4064)
			(end -0.7874 0.4064)
			(stroke
				(width 0.1524)
				(type default)
			)
			(layer "B.SilkS")
		)
		(fp_line
			(start 0.67945 0.3048)
			(end 0.67945 -0.305054)
			(stroke
				(width 0.1)
				(type default)
			)
			(layer "B.Fab")
		)
		(fp_line
			(start 0.67945 -0.305054)
			(end 0.12065 -0.305054)
			(stroke
				(width 0.1)
				(type default)
			)
			(layer "B.Fab")
		)
		(fp_line
			(start 0.12065 0.3048)
			(end 0.67945 0.3048)
			(stroke
				(width 0.1)
				(type default)
			)
			(layer "B.Fab")
		)
		(fp_line
			(start 0.12065 0.2794)
			(end 0.12065 0.3048)
			(stroke
				(width 0.1)
				(type default)
			)
			(layer "B.Fab")
		)
		(fp_line
			(start 0.12065 -0.2794)
			(end -0.12065 -0.2794)
			(stroke
				(width 0.1)
				(type default)
			)
			(layer "B.Fab")
		)
		(fp_line
			(start 0.12065 -0.305054)
			(end 0.12065 -0.2794)
			(stroke
				(width 0.1)
				(type default)
			)
			(layer "B.Fab")
		)
		(fp_line
			(start -0.120396 0.3048)
			(end -0.120396 0.2794)
			(stroke
				(width 0.1)
				(type default)
			)
			(layer "B.Fab")
		)
		(fp_line
			(start -0.120396 0.2794)
			(end 0.12065 0.2794)
			(stroke
				(width 0.1)
				(type default)
			)
			(layer "B.Fab")
		)
		(fp_line
			(start -0.12065 -0.2794)
			(end -0.12065 -0.3048)
			(stroke
				(width 0.1)
				(type default)
			)
			(layer "B.Fab")
		)
		(fp_line
			(start -0.12065 -0.3048)
			(end -0.67945 -0.3048)
			(stroke
				(width 0.1)
				(type default)
			)
			(layer "B.Fab")
		)
		(fp_line
			(start -0.67945 0.3048)
			(end -0.120396 0.3048)
			(stroke
				(width 0.1)
				(type default)
			)
			(layer "B.Fab")
		)
		(fp_line
			(start -0.67945 -0.3048)
			(end -0.67945 0.3048)
			(stroke
				(width 0.1)
				(type default)
			)
			(layer "B.Fab")
		)
		(pad "1" smd circle
			(at 0.40005 0)
			(size 0 0)
			(layers "B.Cu" "B.Mask" "B.Paste")
			(net "SMB_FAN_3V3AUX_SDA")
		)
		(pad "2" smd circle
			(at -0.40005 0)
			(size 0 0)
			(layers "B.Cu" "B.Mask" "B.Paste")
			(net "P3V3_AUX")
		)
	)
	(footprint ""
		(layer "B.Cu")
		(at 118.158768 -210.194144)
		(property "Reference" "C486"
			(at 0 0 0)
			(layer "B.SilkS")
			(hide yes)
			(effects
				(font
					(size 1.27 1.27)
				)
				(justify mirror)
			)
		)
		(property "Value" ""
			(at 0 0 0)
			(layer "B.Fab")
			(effects
				(font
					(size 1.27 1.27)
				)
				(justify mirror)
			)
		)
		(duplicate_pad_numbers_are_jumpers no)
		(fp_line
			(start -1.524 -0.762)
			(end -1.524 0.762)
			(stroke
				(width 0.1524)
				(type default)
			)
			(layer "B.SilkS")
		)
		(fp_line
			(start -1.524 0.762)
			(end 1.524 0.762)
			(stroke
				(width 0.1524)
				(type default)
			)
			(layer "B.SilkS")
		)
		(fp_line
			(start 1.524 -0.762)
			(end -1.524 -0.762)
			(stroke
				(width 0.1524)
				(type default)
			)
			(layer "B.SilkS")
		)
		(fp_line
			(start 1.524 0.762)
			(end 1.524 -0.762)
			(stroke
				(width 0.1524)
				(type default)
			)
			(layer "B.SilkS")
		)
		(fp_line
			(start -1.1049 -0.724916)
			(end 1.1049 -0.724916)
			(stroke
				(width 0.1)
				(type default)
			)
			(layer "B.Fab")
		)
		(fp_line
			(start -1.1049 0.724916)
			(end -1.1049 -0.724916)
			(stroke
				(width 0.1)
				(type default)
			)
			(layer "B.Fab")
		)
		(fp_line
			(start 1.1049 -0.724916)
			(end 1.1049 0.724916)
			(stroke
				(width 0.1)
				(type default)
			)
			(layer "B.Fab")
		)
		(fp_line
			(start 1.1049 0.724916)
			(end -1.1049 0.724916)
			(stroke
				(width 0.1)
				(type default)
			)
			(layer "B.Fab")
		)
		(pad "1" smd rect
			(at 0.889 0)
			(size 1.016 1.27)
			(layers "B.Cu" "B.Mask" "B.Paste")
			(net "PVCCINFAON_CPU1")
		)
		(pad "2" smd rect
			(at -0.889 0)
			(size 1.016 1.27)
			(layers "B.Cu" "B.Mask" "B.Paste")
			(net "GND")
		)
	)
)
